# S9S_MB_2U (Grand Teton) — schematic netlist excerpt (pin names and nets, part order shuffled) for the footprints in the layout excerpt that follows; sources: Cadence DE-HDL packaged netlist, KiCad conversion of 03242023_DA0F0TMBIJ0_F0T_Motherboard_J_brd_V01_OCP.brd

R2791  Q_RES  0 5% EMPTY  pkg 0402LF  page 152 : A = USB2_HOST_BMC_B_DN ; B = USB2_HOST_BMC_B_BUF_DN
R204  Q_RES  1.5K 1% CHIP  pkg 0402LF  page 122 : A = H_CPU1_MEMHOT_OUT_LVC1_R_N ; B = H_CPU1_MEMHOT_OUT_VT_R_N

(kicad_pcb
	(version 20260206)
	(generator "pcbnew")
	(generator_version "10.0")
	(general
		(thickness 1.6)
		(legacy_teardrops no)
	)
	(paper "A4")
	(title_block
		(title "03242023_DA0F0TMBIJ0_F0T_Motherboard_J_brd_V01_OCP.brd")
		(comment 1 "Grand Teton / footprints 4007-4008 of 6105")
	)
	(layers
		(0 "F.Cu" signal "TOP")
		(4 "In1.Cu" signal "GND")
		(6 "In2.Cu" signal "IN1")
		(8 "In3.Cu" signal "GND1")
		(10 "In4.Cu" signal "IN2")
		(12 "In5.Cu" signal "GND2")
		(14 "In6.Cu" signal "IN3")
		(16 "In7.Cu" signal "GND3")
		(18 "In8.Cu" signal "VCC")
		(20 "In9.Cu" signal "VCC1")
		(22 "In10.Cu" signal "GND4")
		(24 "In11.Cu" signal "IN4")
		(26 "In12.Cu" signal "GND5")
		(28 "In13.Cu" signal "IN5")
		(30 "In14.Cu" signal "GND6")
		(32 "In15.Cu" signal "IN6")
		(34 "In16.Cu" signal "GND7")
		(2 "B.Cu" signal "BOTTOM")
		(9 "F.Adhes" user "F.Adhesive")
		(11 "B.Adhes" user "B.Adhesive")
		(13 "F.Paste" user "Package Geometry/Pastemask Top")
		(15 "B.Paste" user "Package Geometry/Pastemask Bottom")
		(5 "F.SilkS" user "Ref Des/Silkscreen Top")
		(7 "B.SilkS" user "Ref Des/Silkscreen Bottom")
		(1 "F.Mask" user "Board Geometry/Soldermask Top")
		(3 "B.Mask" user "Board Geometry/Soldermask Bottom")
		(17 "Dwgs.User" user "User.Drawings")
		(19 "Cmts.User" user "User.Comments")
		(21 "Eco1.User" user "User.Eco1")
		(23 "Eco2.User" user "User.Eco2")
		(25 "Edge.Cuts" user "Board Geometry/Outline")
		(27 "Margin" user)
		(31 "F.CrtYd" user "Package Geometry/Place Bound Top")
		(29 "B.CrtYd" user "Package Geometry/Place Bound Bottom")
		(35 "F.Fab" user "Ref Des/Assembly Top")
		(33 "B.Fab" user "Ref Des/Assembly Bottom")
	)
	(footprint ""
		(layer "F.Cu")
		(at 134.04088 -92.674948 90)
		(property "Reference" "R204"
			(at 0 0 90)
			(layer "F.SilkS")
			(hide yes)
			(effects
				(font
					(size 1.27 1.27)
				)
			)
		)
		(property "Value" ""
			(at 0 0 90)
			(layer "F.Fab")
			(effects
				(font
					(size 1.27 1.27)
				)
			)
		)
		(duplicate_pad_numbers_are_jumpers no)
		(fp_line
			(start 0.7874 -0.4064)
			(end 0.7874 0.4064)
			(stroke
				(width 0.1524)
				(type default)
			)
			(layer "F.SilkS")
		)
		(fp_line
			(start -0.7874 -0.4064)
			(end 0.7874 -0.4064)
			(stroke
				(width 0.1524)
				(type default)
			)
			(layer "F.SilkS")
		)
		(fp_line
			(start 0.7874 0.4064)
			(end -0.7874 0.4064)
			(stroke
				(width 0.1524)
				(type default)
			)
			(layer "F.SilkS")
		)
		(fp_line
			(start -0.7874 0.4064)
			(end -0.7874 -0.4064)
			(stroke
				(width 0.1524)
				(type default)
			)
			(layer "F.SilkS")
		)
		(fp_line
			(start -0.12065 -0.305054)
			(end -0.12065 -0.2794)
			(stroke
				(width 0.1)
				(type default)
			)
			(layer "F.Fab")
		)
		(fp_line
			(start -0.67945 -0.305054)
			(end -0.12065 -0.305054)
			(stroke
				(width 0.1)
				(type default)
			)
			(layer "F.Fab")
		)
		(fp_line
			(start 0.67945 -0.3048)
			(end 0.67945 0.3048)
			(stroke
				(width 0.1)
				(type default)
			)
			(layer "F.Fab")
		)
		(fp_line
			(start 0.12065 -0.3048)
			(end 0.67945 -0.3048)
			(stroke
				(width 0.1)
				(type default)
			)
			(layer "F.Fab")
		)
		(fp_line
			(start 0.12065 -0.2794)
			(end 0.12065 -0.3048)
			(stroke
				(width 0.1)
				(type default)
			)
			(layer "F.Fab")
		)
		(fp_line
			(start -0.12065 -0.2794)
			(end 0.12065 -0.2794)
			(stroke
				(width 0.1)
				(type default)
			)
			(layer "F.Fab")
		)
		(fp_line
			(start 0.120396 0.2794)
			(end -0.12065 0.2794)
			(stroke
				(width 0.1)
				(type default)
			)
			(layer "F.Fab")
		)
		(fp_line
			(start -0.12065 0.2794)
			(end -0.12065 0.3048)
			(stroke
				(width 0.1)
				(type default)
			)
			(layer "F.Fab")
		)
		(fp_line
			(start 0.67945 0.3048)
			(end 0.120396 0.3048)
			(stroke
				(width 0.1)
				(type default)
			)
			(layer "F.Fab")
		)
		(fp_line
			(start 0.120396 0.3048)
			(end 0.120396 0.2794)
			(stroke
				(width 0.1)
				(type default)
			)
			(layer "F.Fab")
		)
		(fp_line
			(start -0.12065 0.3048)
			(end -0.67945 0.3048)
			(stroke
				(width 0.1)
				(type default)
			)
			(layer "F.Fab")
		)
		(fp_line
			(start -0.67945 0.3048)
			(end -0.67945 -0.305054)
			(stroke
				(width 0.1)
				(type default)
			)
			(layer "F.Fab")
		)
		(pad "1" smd circle
			(at -0.40005 0 90)
			(size 0 0)
			(layers "F.Cu" "F.Mask" "F.Paste")
			(net "H_CPU1_MEMHOT_OUT_LVC1_R_N")
		)
		(pad "2" smd circle
			(at 0.40005 0 90)
			(size 0 0)
			(layers "F.Cu" "F.Mask" "F.Paste")
			(net "H_CPU1_MEMHOT_OUT_VT_R_N")
		)
	)
	(footprint ""
		(layer "F.Cu")
		(at 16.645382 -105.56621 90)
		(property "Reference" "R2791"
			(at 0 0 90)
			(layer "F.SilkS")
			(hide yes)
			(effects
				(font
					(size 1.27 1.27)
				)
			)
		)
		(property "Value" ""
			(at 0 0 90)
			(layer "F.Fab")
			(effects
				(font
					(size 1.27 1.27)
				)
			)
		)
		(duplicate_pad_numbers_are_jumpers no)
		(fp_line
			(start -0.01651 -0.4064)
			(end 0.7874 -0.4064)
			(stroke
				(width 0.1524)
				(type default)
			)
			(layer "F.SilkS")
		)
		(fp_line
			(start 0.7874 0.4064)
			(end -0.02921 0.4064)
			(stroke
				(width 0.1524)
				(type default)
			)
			(layer "F.SilkS")
		)
		(fp_line
			(start -0.7874 0.4064)
			(end -0.7874 -0.4064)
			(stroke
				(width 0.1524)
				(type default)
			)
			(layer "F.SilkS")
		)
		(fp_line
			(start -0.12065 -0.305054)
			(end -0.12065 -0.2794)
			(stroke
				(width 0.1)
				(type default)
			)
			(layer "F.Fab")
		)
		(fp_line
			(start -0.67945 -0.305054)
			(end -0.12065 -0.305054)
			(stroke
				(width 0.1)
				(type default)
			)
			(layer "F.Fab")
		)
		(fp_line
			(start 0.67945 -0.3048)
			(end 0.67945 0.3048)
			(stroke
				(width 0.1)
				(type default)
			)
			(layer "F.Fab")
		)
		(fp_line
			(start 0.12065 -0.3048)
			(end 0.67945 -0.3048)
			(stroke
				(width 0.1)
				(type default)
			)
			(layer "F.Fab")
		)
		(fp_line
			(start 0.12065 -0.2794)
			(end 0.12065 -0.3048)
			(stroke
				(width 0.1)
				(type default)
			)
			(layer "F.Fab")
		)
		(fp_line
			(start -0.12065 -0.2794)
			(end 0.12065 -0.2794)
			(stroke
				(width 0.1)
				(type default)
			)
			(layer "F.Fab")
		)
		(fp_line
			(start 0.120396 0.2794)
			(end -0.12065 0.2794)
			(stroke
				(width 0.1)
				(type default)
			)
			(layer "F.Fab")
		)
		(fp_line
			(start -0.12065 0.2794)
			(end -0.12065 0.3048)
			(stroke
				(width 0.1)
				(type default)
			)
			(layer "F.Fab")
		)
		(fp_line
			(start 0.67945 0.3048)
			(end 0.120396 0.3048)
			(stroke
				(width 0.1)
				(type default)
			)
			(layer "F.Fab")
		)
		(fp_line
			(start 0.120396 0.3048)
			(end 0.120396 0.2794)
			(stroke
				(width 0.1)
				(type default)
			)
			(layer "F.Fab")
		)
		(fp_line
			(start -0.12065 0.3048)
			(end -0.67945 0.3048)
			(stroke
				(width 0.1)
				(type default)
			)
			(layer "F.Fab")
		)
		(fp_line
			(start -0.67945 0.3048)
			(end -0.67945 -0.305054)
			(stroke
				(width 0.1)
				(type default)
			)
			(layer "F.Fab")
		)
		(pad "1" smd rect
			(at -0.40005 0 270)
			(size 0.4572 0.508)
			(layers "F.Cu" "F.Mask" "F.Paste")
			(net "USB2_HOST_BMC_B_DN")
		)
		(pad "2" smd rect
			(at 0.40005 0 270)
			(size 0.4572 0.508)
			(layers "F.Cu" "F.Mask" "F.Paste")
			(net "USB2_HOST_BMC_B_BUF_DN")
		)
	)
)
